# T6G (Grand Teton) — schematic netlist excerpt (pin names and nets, part order shuffled) for the footprints in the layout excerpt that follows; sources: Cadence DE-HDL packaged netlist, KiCad conversion of 04192023_DAF0TMB3IC0_F0TG_MB_C_brd_V02_OCP.brd

C1810  Q_CAP  0.1UF 25V 10% X7R  pkg 0402  page 140 : A = P3V3_AUX ; B = GND
PC206_11P0_2  Q_CAP  2.2UF 10V 10% X6S  pkg C0402  page 208 : A = PVDD11_S3_P0_PVCC ; B = GND

(kicad_pcb
	(version 20260206)
	(generator "pcbnew")
	(generator_version "10.0")
	(general
		(thickness 1.6)
		(legacy_teardrops no)
	)
	(paper "A4")
	(title_block
		(title "04192023_DAF0TMB3IC0_F0TG_MB_C_brd_V02_OCP.brd")
		(comment 1 "Grand Teton / footprints 1259-1260 of 8354")
	)
	(layers
		(0 "F.Cu" signal "TOP")
		(4 "In1.Cu" signal "GND")
		(6 "In2.Cu" signal "IN1")
		(8 "In3.Cu" signal "GND1")
		(10 "In4.Cu" signal "IN2")
		(12 "In5.Cu" signal "GND2")
		(14 "In6.Cu" signal "IN3")
		(16 "In7.Cu" signal "GND3")
		(18 "In8.Cu" signal "VCC")
		(20 "In9.Cu" signal "VCC1")
		(22 "In10.Cu" signal "GND4")
		(24 "In11.Cu" signal "IN4")
		(26 "In12.Cu" signal "GND5")
		(28 "In13.Cu" signal "IN5")
		(30 "In14.Cu" signal "GND6")
		(32 "In15.Cu" signal "IN6")
		(34 "In16.Cu" signal "GND7")
		(2 "B.Cu" signal "BOTTOM")
		(9 "F.Adhes" user "F.Adhesive")
		(11 "B.Adhes" user "B.Adhesive")
		(13 "F.Paste" user "Package Geometry/Pastemask Top")
		(15 "B.Paste" user "Package Geometry/Pastemask Bottom")
		(5 "F.SilkS" user "Ref Des/Silkscreen Top")
		(7 "B.SilkS" user "Ref Des/Silkscreen Bottom")
		(1 "F.Mask" user "Board Geometry/Soldermask Top")
		(3 "B.Mask" user "Board Geometry/Soldermask Bottom")
		(17 "Dwgs.User" user "User.Drawings")
		(19 "Cmts.User" user "User.Comments")
		(21 "Eco1.User" user "User.Eco1")
		(23 "Eco2.User" user "User.Eco2")
		(25 "Edge.Cuts" user "Board Geometry/Outline")
		(27 "Margin" user)
		(31 "F.CrtYd" user "Package Geometry/Place Bound Top")
		(29 "B.CrtYd" user "Package Geometry/Place Bound Bottom")
		(35 "F.Fab" user "Ref Des/Assembly Top")
		(33 "B.Fab" user "Ref Des/Assembly Bottom")
	)
	(footprint ""
		(layer "F.Cu")
		(at 15.58417 -71.210678)
		(property "Reference" "C1810"
			(at 0 0 0)
			(layer "F.SilkS")
			(hide yes)
			(effects
				(font
					(size 1.27 1.27)
				)
			)
		)
		(property "Value" ""
			(at 0 0 0)
			(layer "F.Fab")
			(effects
				(font
					(size 1.27 1.27)
				)
			)
		)
		(duplicate_pad_numbers_are_jumpers no)
		(fp_line
			(start -0.7874 -0.4064)
			(end 0.7874 -0.4064)
			(stroke
				(width 0.1524)
				(type default)
			)
			(layer "F.SilkS")
		)
		(fp_line
			(start -0.7874 0.4064)
			(end -0.7874 -0.4064)
			(stroke
				(width 0.1524)
				(type default)
			)
			(layer "F.SilkS")
		)
		(fp_line
			(start 0.7874 -0.4064)
			(end 0.7874 0.4064)
			(stroke
				(width 0.1524)
				(type default)
			)
			(layer "F.SilkS")
		)
		(fp_line
			(start 0.7874 0.4064)
			(end -0.7874 0.4064)
			(stroke
				(width 0.1524)
				(type default)
			)
			(layer "F.SilkS")
		)
		(fp_line
			(start -0.67945 -0.305054)
			(end -0.12065 -0.305054)
			(stroke
				(width 0.1)
				(type default)
			)
			(layer "F.Fab")
		)
		(fp_line
			(start -0.67945 0.3048)
			(end -0.67945 -0.305054)
			(stroke
				(width 0.1)
				(type default)
			)
			(layer "F.Fab")
		)
		(fp_line
			(start -0.12065 -0.305054)
			(end -0.12065 -0.2794)
			(stroke
				(width 0.1)
				(type default)
			)
			(layer "F.Fab")
		)
		(fp_line
			(start -0.12065 -0.2794)
			(end 0.12065 -0.2794)
			(stroke
				(width 0.1)
				(type default)
			)
			(layer "F.Fab")
		)
		(fp_line
			(start -0.12065 0.2794)
			(end -0.12065 0.3048)
			(stroke
				(width 0.1)
				(type default)
			)
			(layer "F.Fab")
		)
		(fp_line
			(start -0.12065 0.3048)
			(end -0.67945 0.3048)
			(stroke
				(width 0.1)
				(type default)
			)
			(layer "F.Fab")
		)
		(fp_line
			(start 0.120396 0.2794)
			(end -0.12065 0.2794)
			(stroke
				(width 0.1)
				(type default)
			)
			(layer "F.Fab")
		)
		(fp_line
			(start 0.120396 0.3048)
			(end 0.120396 0.2794)
			(stroke
				(width 0.1)
				(type default)
			)
			(layer "F.Fab")
		)
		(fp_line
			(start 0.12065 -0.3048)
			(end 0.67945 -0.3048)
			(stroke
				(width 0.1)
				(type default)
			)
			(layer "F.Fab")
		)
		(fp_line
			(start 0.12065 -0.2794)
			(end 0.12065 -0.3048)
			(stroke
				(width 0.1)
				(type default)
			)
			(layer "F.Fab")
		)
		(fp_line
			(start 0.67945 -0.3048)
			(end 0.67945 0.3048)
			(stroke
				(width 0.1)
				(type default)
			)
			(layer "F.Fab")
		)
		(fp_line
			(start 0.67945 0.3048)
			(end 0.120396 0.3048)
			(stroke
				(width 0.1)
				(type default)
			)
			(layer "F.Fab")
		)
		(pad "1" smd circle
			(at -0.40005 0)
			(size 0 0)
			(layers "F.Cu" "F.Mask" "F.Paste")
			(net "P3V3_AUX")
		)
		(pad "2" smd circle
			(at 0.40005 0)
			(size 0 0)
			(layers "F.Cu" "F.Mask" "F.Paste")
			(net "GND")
		)
	)
	(footprint ""
		(layer "F.Cu")
		(at 428.287688 -351.13849 -90)
		(property "Reference" "PC206_11P0_2"
			(at 0 0 270)
			(layer "F.SilkS")
			(hide yes)
			(effects
				(font
					(size 1.27 1.27)
				)
			)
		)
		(property "Value" ""
			(at 0 0 270)
			(layer "F.Fab")
			(effects
				(font
					(size 1.27 1.27)
				)
			)
		)
		(duplicate_pad_numbers_are_jumpers no)
		(fp_line
			(start -0.7874 0.4064)
			(end -0.7874 -0.4064)
			(stroke
				(width 0.1524)
				(type default)
			)
			(layer "F.SilkS")
		)
		(fp_line
			(start 0.7874 0.4064)
			(end -0.7874 0.4064)
			(stroke
				(width 0.1524)
				(type default)
			)
			(layer "F.SilkS")
		)
		(fp_line
			(start -0.7874 -0.4064)
			(end 0.7874 -0.4064)
			(stroke
				(width 0.1524)
				(type default)
			)
			(layer "F.SilkS")
		)
		(fp_line
			(start 0.7874 -0.4064)
			(end 0.7874 0.4064)
			(stroke
				(width 0.1524)
				(type default)
			)
			(layer "F.SilkS")
		)
		(fp_line
			(start -0.67945 0.3048)
			(end -0.67945 -0.305054)
			(stroke
				(width 0.1)
				(type default)
			)
			(layer "F.Fab")
		)
		(fp_line
			(start -0.12065 0.3048)
			(end -0.67945 0.3048)
			(stroke
				(width 0.1)
				(type default)
			)
			(layer "F.Fab")
		)
		(fp_line
			(start 0.120396 0.3048)
			(end 0.120396 0.2794)
			(stroke
				(width 0.1)
				(type default)
			)
			(layer "F.Fab")
		)
		(fp_line
			(start 0.67945 0.3048)
			(end 0.120396 0.3048)
			(stroke
				(width 0.1)
				(type default)
			)
			(layer "F.Fab")
		)
		(fp_line
			(start -0.12065 0.2794)
			(end -0.12065 0.3048)
			(stroke
				(width 0.1)
				(type default)
			)
			(layer "F.Fab")
		)
		(fp_line
			(start 0.120396 0.2794)
			(end -0.12065 0.2794)
			(stroke
				(width 0.1)
				(type default)
			)
			(layer "F.Fab")
		)
		(fp_line
			(start -0.12065 -0.2794)
			(end 0.12065 -0.2794)
			(stroke
				(width 0.1)
				(type default)
			)
			(layer "F.Fab")
		)
		(fp_line
			(start 0.12065 -0.2794)
			(end 0.12065 -0.3048)
			(stroke
				(width 0.1)
				(type default)
			)
			(layer "F.Fab")
		)
		(fp_line
			(start 0.12065 -0.3048)
			(end 0.67945 -0.3048)
			(stroke
				(width 0.1)
				(type default)
			)
			(layer "F.Fab")
		)
		(fp_line
			(start 0.67945 -0.3048)
			(end 0.67945 0.3048)
			(stroke
				(width 0.1)
				(type default)
			)
			(layer "F.Fab")
		)
		(fp_line
			(start -0.67945 -0.305054)
			(end -0.12065 -0.305054)
			(stroke
				(width 0.1)
				(type default)
			)
			(layer "F.Fab")
		)
		(fp_line
			(start -0.12065 -0.305054)
			(end -0.12065 -0.2794)
			(stroke
				(width 0.1)
				(type default)
			)
			(layer "F.Fab")
		)
		(pad "1" smd circle
			(at -0.40005 0 270)
			(size 0 0)
			(layers "F.Cu" "F.Mask" "F.Paste")
			(net "PVDD11_S3_P0_PVCC")
		)
		(pad "2" smd circle
			(at 0.40005 0 270)
			(size 0 0)
			(layers "F.Cu" "F.Mask" "F.Paste")
			(net "GND")
		)
	)
)
